(kicad_pcb
	(version 20260206)
	(generator "pcbnew")
	(generator_version "10.0")
	(general
		(thickness 1.6)
		(legacy_teardrops no)
	)
	(paper "A4")
	(title_block
		(title "01162023_DA0F0TEBIF0_F0T_Expander_BD_F_brd_V02_OCP.brd")
		(comment 1 "Grand Teton / footprints 7573-7578 of 9728")
	)
	(layers
		(0 "F.Cu" signal "TOP")
		(4 "In1.Cu" signal "GND")
		(6 "In2.Cu" signal "VCC")
		(8 "In3.Cu" signal "VCC1")
		(10 "In4.Cu" signal "GND1")
		(12 "In5.Cu" signal "IN1")
		(14 "In6.Cu" signal "GND2")
		(16 "In7.Cu" signal "IN2")
		(18 "In8.Cu" signal "GND3")
		(20 "In9.Cu" signal "IN3")
		(22 "In10.Cu" signal "GND4")
		(24 "In11.Cu" signal "IN4")
		(26 "In12.Cu" signal "GND5")
		(28 "In13.Cu" signal "IN5")
		(30 "In14.Cu" signal "GND6")
		(32 "In15.Cu" signal "IN6")
		(34 "In16.Cu" signal "GND7")
		(2 "B.Cu" signal "BOTTOM")
		(9 "F.Adhes" user "F.Adhesive")
		(11 "B.Adhes" user "B.Adhesive")
		(13 "F.Paste" user "Package Geometry/Pastemask Top")
		(15 "B.Paste" user "Package Geometry/Pastemask Bottom")
		(5 "F.SilkS" user "Ref Des/Silkscreen Top")
		(7 "B.SilkS" user "Ref Des/Silkscreen Bottom")
		(1 "F.Mask" user "Board Geometry/Soldermask Top")
		(3 "B.Mask" user "Board Geometry/Soldermask Bottom")
		(17 "Dwgs.User" user "User.Drawings")
		(19 "Cmts.User" user "User.Comments")
		(21 "Eco1.User" user "User.Eco1")
		(23 "Eco2.User" user "User.Eco2")
		(25 "Edge.Cuts" user "Board Geometry/Outline")
		(27 "Margin" user)
		(31 "F.CrtYd" user "Package Geometry/Place Bound Top")
		(29 "B.CrtYd" user "Package Geometry/Place Bound Bottom")
		(35 "F.Fab" user "Ref Des/Assembly Top")
		(33 "B.Fab" user "Ref Des/Assembly Bottom")
	)
	(footprint ""
		(layer "B.Cu")
		(at 257.529838 -228.268784 90)
		(property "Reference" "R3481"
			(at 0 0 90)
			(layer "B.SilkS")
			(hide yes)
			(effects
				(font
					(size 1.27 1.27)
				)
				(justify mirror)
			)
		)
		(property "Value" ""
			(at 0 0 90)
			(layer "B.Fab")
			(effects
				(font
					(size 1.27 1.27)
				)
				(justify mirror)
			)
		)
		(duplicate_pad_numbers_are_jumpers no)
		(fp_line
			(start 0.7874 -0.4064)
			(end -0.7874 -0.4064)
			(stroke
				(width 0.1524)
				(type default)
			)
			(layer "B.SilkS")
		)
		(fp_line
			(start -0.7874 -0.4064)
			(end -0.7874 0.4064)
			(stroke
				(width 0.1524)
				(type default)
			)
			(layer "B.SilkS")
		)
		(fp_line
			(start 0.7874 0.4064)
			(end 0.7874 -0.4064)
			(stroke
				(width 0.1524)
				(type default)
			)
			(layer "B.SilkS")
		)
		(fp_line
			(start -0.7874 0.4064)
			(end 0.7874 0.4064)
			(stroke
				(width 0.1524)
				(type default)
			)
			(layer "B.SilkS")
		)
		(fp_line
			(start 0.67945 -0.305054)
			(end 0.12065 -0.305054)
			(stroke
				(width 0.1)
				(type default)
			)
			(layer "B.Fab")
		)
		(fp_line
			(start 0.12065 -0.305054)
			(end 0.12065 -0.2794)
			(stroke
				(width 0.1)
				(type default)
			)
			(layer "B.Fab")
		)
		(fp_line
			(start -0.12065 -0.3048)
			(end -0.67945 -0.3048)
			(stroke
				(width 0.1)
				(type default)
			)
			(layer "B.Fab")
		)
		(fp_line
			(start -0.67945 -0.3048)
			(end -0.67945 0.3048)
			(stroke
				(width 0.1)
				(type default)
			)
			(layer "B.Fab")
		)
		(fp_line
			(start 0.12065 -0.2794)
			(end -0.12065 -0.2794)
			(stroke
				(width 0.1)
				(type default)
			)
			(layer "B.Fab")
		)
		(fp_line
			(start -0.12065 -0.2794)
			(end -0.12065 -0.3048)
			(stroke
				(width 0.1)
				(type default)
			)
			(layer "B.Fab")
		)
		(fp_line
			(start 0.12065 0.2794)
			(end 0.12065 0.3048)
			(stroke
				(width 0.1)
				(type default)
			)
			(layer "B.Fab")
		)
		(fp_line
			(start -0.120396 0.2794)
			(end 0.12065 0.2794)
			(stroke
				(width 0.1)
				(type default)
			)
			(layer "B.Fab")
		)
		(fp_line
			(start 0.67945 0.3048)
			(end 0.67945 -0.305054)
			(stroke
				(width 0.1)
				(type default)
			)
			(layer "B.Fab")
		)
		(fp_line
			(start 0.12065 0.3048)
			(end 0.67945 0.3048)
			(stroke
				(width 0.1)
				(type default)
			)
			(layer "B.Fab")
		)
		(fp_line
			(start -0.120396 0.3048)
			(end -0.120396 0.2794)
			(stroke
				(width 0.1)
				(type default)
			)
			(layer "B.Fab")
		)
		(fp_line
			(start -0.67945 0.3048)
			(end -0.120396 0.3048)
			(stroke
				(width 0.1)
				(type default)
			)
			(layer "B.Fab")
		)
		(pad "1" smd circle
			(at 0.40005 0 270)
			(size 0 0)
			(layers "B.Cu" "B.Mask" "B.Paste")
			(net "SPI_PEX2_CS_MUX_N")
		)
		(pad "2" smd circle
			(at -0.40005 0 270)
			(size 0 0)
			(layers "B.Cu" "B.Mask" "B.Paste")
			(net "SPI_PEX2_CS_MUX_R_N")
		)
	)
	(footprint ""
		(layer "B.Cu")
		(at 203.106274 -259.311648 90)
		(property "Reference" "R6360"
			(at 0 0 90)
			(layer "B.SilkS")
			(hide yes)
			(effects
				(font
					(size 1.27 1.27)
				)
				(justify mirror)
			)
		)
		(property "Value" ""
			(at 0 0 90)
			(layer "B.Fab")
			(effects
				(font
					(size 1.27 1.27)
				)
				(justify mirror)
			)
		)
		(duplicate_pad_numbers_are_jumpers no)
		(fp_line
			(start 0.7874 -0.4064)
			(end -0.7874 -0.4064)
			(stroke
				(width 0.1524)
				(type default)
			)
			(layer "B.SilkS")
		)
		(fp_line
			(start -0.7874 -0.4064)
			(end -0.7874 0.4064)
			(stroke
				(width 0.1524)
				(type default)
			)
			(layer "B.SilkS")
		)
		(fp_line
			(start 0.7874 0.4064)
			(end 0.7874 -0.4064)
			(stroke
				(width 0.1524)
				(type default)
			)
			(layer "B.SilkS")
		)
		(fp_line
			(start -0.7874 0.4064)
			(end 0.7874 0.4064)
			(stroke
				(width 0.1524)
				(type default)
			)
			(layer "B.SilkS")
		)
		(fp_line
			(start 0.67945 -0.305054)
			(end 0.12065 -0.305054)
			(stroke
				(width 0.1)
				(type default)
			)
			(layer "B.Fab")
		)
		(fp_line
			(start 0.12065 -0.305054)
			(end 0.12065 -0.2794)
			(stroke
				(width 0.1)
				(type default)
			)
			(layer "B.Fab")
		)
		(fp_line
			(start -0.12065 -0.3048)
			(end -0.67945 -0.3048)
			(stroke
				(width 0.1)
				(type default)
			)
			(layer "B.Fab")
		)
		(fp_line
			(start -0.67945 -0.3048)
			(end -0.67945 0.3048)
			(stroke
				(width 0.1)
				(type default)
			)
			(layer "B.Fab")
		)
		(fp_line
			(start 0.12065 -0.2794)
			(end -0.12065 -0.2794)
			(stroke
				(width 0.1)
				(type default)
			)
			(layer "B.Fab")
		)
		(fp_line
			(start -0.12065 -0.2794)
			(end -0.12065 -0.3048)
			(stroke
				(width 0.1)
				(type default)
			)
			(layer "B.Fab")
		)
		(fp_line
			(start 0.12065 0.2794)
			(end 0.12065 0.3048)
			(stroke
				(width 0.1)
				(type default)
			)
			(layer "B.Fab")
		)
		(fp_line
			(start -0.120396 0.2794)
			(end 0.12065 0.2794)
			(stroke
				(width 0.1)
				(type default)
			)
			(layer "B.Fab")
		)
		(fp_line
			(start 0.67945 0.3048)
			(end 0.67945 -0.305054)
			(stroke
				(width 0.1)
				(type default)
			)
			(layer "B.Fab")
		)
		(fp_line
			(start 0.12065 0.3048)
			(end 0.67945 0.3048)
			(stroke
				(width 0.1)
				(type default)
			)
			(layer "B.Fab")
		)
		(fp_line
			(start -0.120396 0.3048)
			(end -0.120396 0.2794)
			(stroke
				(width 0.1)
				(type default)
			)
			(layer "B.Fab")
		)
		(fp_line
			(start -0.67945 0.3048)
			(end -0.120396 0.3048)
			(stroke
				(width 0.1)
				(type default)
			)
			(layer "B.Fab")
		)
		(pad "1" smd circle
			(at 0.40005 0 270)
			(size 0 0)
			(layers "B.Cu" "B.Mask" "B.Paste")
			(net "P3V3_AUX")
		)
		(pad "2" smd circle
			(at -0.40005 0 270)
			(size 0 0)
			(layers "B.Cu" "B.Mask" "B.Paste")
			(net "RST_PEX_MUX_R_N")
		)
	)
	(footprint ""
		(layer "B.Cu")
		(at 385.425696 -247.311926 -90)
		(property "Reference" "R942"
			(at 0 0 90)
			(layer "B.SilkS")
			(hide yes)
			(effects
				(font
					(size 1.27 1.27)
				)
				(justify mirror)
			)
		)
		(property "Value" ""
			(at 0 0 90)
			(layer "B.Fab")
			(effects
				(font
					(size 1.27 1.27)
				)
				(justify mirror)
			)
		)
		(duplicate_pad_numbers_are_jumpers no)
		(fp_line
			(start -0.7874 0.4064)
			(end 0.7874 0.4064)
			(stroke
				(width 0.1524)
				(type default)
			)
			(layer "B.SilkS")
		)
		(fp_line
			(start 0.7874 0.4064)
			(end 0.7874 -0.4064)
			(stroke
				(width 0.1524)
				(type default)
			)
			(layer "B.SilkS")
		)
		(fp_line
			(start -0.7874 -0.4064)
			(end -0.7874 0.4064)
			(stroke
				(width 0.1524)
				(type default)
			)
			(layer "B.SilkS")
		)
		(fp_line
			(start 0.7874 -0.4064)
			(end -0.7874 -0.4064)
			(stroke
				(width 0.1524)
				(type default)
			)
			(layer "B.SilkS")
		)
		(fp_line
			(start -0.67945 0.3048)
			(end -0.120396 0.3048)
			(stroke
				(width 0.1)
				(type default)
			)
			(layer "B.Fab")
		)
		(fp_line
			(start -0.120396 0.3048)
			(end -0.120396 0.2794)
			(stroke
				(width 0.1)
				(type default)
			)
			(layer "B.Fab")
		)
		(fp_line
			(start 0.12065 0.3048)
			(end 0.67945 0.3048)
			(stroke
				(width 0.1)
				(type default)
			)
			(layer "B.Fab")
		)
		(fp_line
			(start 0.67945 0.3048)
			(end 0.67945 -0.305054)
			(stroke
				(width 0.1)
				(type default)
			)
			(layer "B.Fab")
		)
		(fp_line
			(start -0.120396 0.2794)
			(end 0.12065 0.2794)
			(stroke
				(width 0.1)
				(type default)
			)
			(layer "B.Fab")
		)
		(fp_line
			(start 0.12065 0.2794)
			(end 0.12065 0.3048)
			(stroke
				(width 0.1)
				(type default)
			)
			(layer "B.Fab")
		)
		(fp_line
			(start -0.12065 -0.2794)
			(end -0.12065 -0.3048)
			(stroke
				(width 0.1)
				(type default)
			)
			(layer "B.Fab")
		)
		(fp_line
			(start 0.12065 -0.2794)
			(end -0.12065 -0.2794)
			(stroke
				(width 0.1)
				(type default)
			)
			(layer "B.Fab")
		)
		(fp_line
			(start -0.67945 -0.3048)
			(end -0.67945 0.3048)
			(stroke
				(width 0.1)
				(type default)
			)
			(layer "B.Fab")
		)
		(fp_line
			(start -0.12065 -0.3048)
			(end -0.67945 -0.3048)
			(stroke
				(width 0.1)
				(type default)
			)
			(layer "B.Fab")
		)
		(fp_line
			(start 0.12065 -0.305054)
			(end 0.12065 -0.2794)
			(stroke
				(width 0.1)
				(type default)
			)
			(layer "B.Fab")
		)
		(fp_line
			(start 0.67945 -0.305054)
			(end 0.12065 -0.305054)
			(stroke
				(width 0.1)
				(type default)
			)
			(layer "B.Fab")
		)
		(pad "1" smd circle
			(at 0.40005 0 90)
			(size 0 0)
			(layers "B.Cu" "B.Mask" "B.Paste")
			(net "UART_PEX3_SDB_BUF_R_RX")
		)
		(pad "2" smd circle
			(at -0.40005 0 90)
			(size 0 0)
			(layers "B.Cu" "B.Mask" "B.Paste")
			(net "UART_PEX3_SDB_BUF_RX")
		)
	)
	(footprint ""
		(layer "B.Cu")
		(at 402.909024 20.575524 180)
		(property "Reference" "DE05F_4"
			(at -2.805176 -3.098546 0)
			(unlocked yes)
			(layer "B.SilkS")
			(effects
				(font
					(size 0.7874 0.5842)
					(thickness 0.1524)
				)
				(justify left mirror)
			)
		)
		(property "Value" ""
			(at 0 0 0)
			(layer "B.Fab")
			(effects
				(font
					(size 1.27 1.27)
				)
				(justify mirror)
			)
		)
		(duplicate_pad_numbers_are_jumpers no)
		(fp_line
			(start 1.2192 2.1082)
			(end 1.2192 -2.1082)
			(stroke
				(width 0.1524)
				(type default)
			)
			(layer "B.SilkS")
		)
		(fp_line
			(start 1.2192 -2.1082)
			(end -1.2192 -2.1082)
			(stroke
				(width 0.1524)
				(type default)
			)
			(layer "B.SilkS")
		)
		(fp_line
			(start -1.2192 2.1082)
			(end 1.2192 2.1082)
			(stroke
				(width 0.1524)
				(type default)
			)
			(layer "B.SilkS")
		)
		(fp_line
			(start -1.2192 -2.1082)
			(end -1.2192 2.1082)
			(stroke
				(width 0.1524)
				(type default)
			)
			(layer "B.SilkS")
		)
		(pad "" np_thru_hole circle
			(at -3.4671 -1.27 90)
			(size 1.0414 1.0414)
			(drill 1.0414)
			(layers "*.Cu" "*.Mask")
			(clearance 0.381)
			(thermal_gap 0.381)
		)
		(pad "" np_thru_hole circle
			(at -3.4671 1.27 90)
			(size 1.0414 1.0414)
			(drill 1.0414)
			(layers "*.Cu" "*.Mask")
			(clearance 0.381)
			(thermal_gap 0.381)
		)
		(pad "" np_thru_hole circle
			(at 2.8829 -1.27 90)
			(size 1.0414 1.0414)
			(drill 1.0414)
			(layers "*.Cu" "*.Mask")
			(clearance 0.381)
			(thermal_gap 0.381)
		)
		(pad "" np_thru_hole circle
			(at 2.8829 1.27 90)
			(size 1.0414 1.0414)
			(drill 1.0414)
			(layers "*.Cu" "*.Mask")
			(clearance 0.381)
			(thermal_gap 0.381)
		)
		(pad "1" smd rect
			(at -0.8255 -0.249936 90)
			(size 0.3048 0.508)
			(layers "B.Cu" "B.Mask" "B.Paste")
			(net "85_5INCH_IN5_DN")
		)
		(pad "2" smd rect
			(at -0.8255 0.249936 90)
			(size 0.3048 0.508)
			(layers "B.Cu" "B.Mask" "B.Paste")
			(net "85_5INCH_IN5_DP")
		)
		(pad "3" smd circle
			(at 0 0)
			(size 0 0)
			(layers "B.Cu" "B.Mask" "B.Paste")
			(net "COUPON_GND2")
		)
		(zone
			(layers "F.Cu" "B.Cu" "In1.Cu" "In2.Cu" "In3.Cu" "In4.Cu" "In5.Cu" "In6.Cu"
				"In7.Cu" "In8.Cu" "In9.Cu" "In10.Cu" "In11.Cu" "In12.Cu" "In13.Cu" "In14.Cu"
				"In15.Cu" "In16.Cu"
			)
			(hatch none 0.5)
			(connect_pads
				(clearance 0)
			)
			(min_thickness 0.25)
			(keepout
				(tracks not_allowed)
				(vias allowed)
				(pads allowed)
				(copperpour not_allowed)
				(footprints allowed)
			)
			(placement
				(enabled no)
				(sheetname "")
			)
			(fill
				(thermal_gap 0.5)
				(thermal_bridge_width 0.5)
				(island_removal_mode 0)
			)
			(polygon
				(pts
					(arc
						(start 400.953224 19.305524)
						(mid 399.099024 19.305524)
						(end 400.953224 19.305524)
					)
				)
			)
		)
		(zone
			(layers "F.Cu" "B.Cu" "In1.Cu" "In2.Cu" "In3.Cu" "In4.Cu" "In5.Cu" "In6.Cu"
				"In7.Cu" "In8.Cu" "In9.Cu" "In10.Cu" "In11.Cu" "In12.Cu" "In13.Cu" "In14.Cu"
				"In15.Cu" "In16.Cu"
			)
			(hatch none 0.5)
			(connect_pads
				(clearance 0)
			)
			(min_thickness 0.25)
			(keepout
				(tracks not_allowed)
				(vias allowed)
				(pads allowed)
				(copperpour not_allowed)
				(footprints allowed)
			)
			(placement
				(enabled no)
				(sheetname "")
			)
			(fill
				(thermal_gap 0.5)
				(thermal_bridge_width 0.5)
				(island_removal_mode 0)
			)
			(polygon
				(pts
					(arc
						(start 400.953224 21.845524)
						(mid 399.099024 21.845524)
						(end 400.953224 21.845524)
					)
				)
			)
		)
		(zone
			(layers "F.Cu" "B.Cu" "In1.Cu" "In2.Cu" "In3.Cu" "In4.Cu" "In5.Cu" "In6.Cu"
				"In7.Cu" "In8.Cu" "In9.Cu" "In10.Cu" "In11.Cu" "In12.Cu" "In13.Cu" "In14.Cu"
				"In15.Cu" "In16.Cu"
			)
			(hatch none 0.5)
			(connect_pads
				(clearance 0)
			)
			(min_thickness 0.25)
			(keepout
				(tracks not_allowed)
				(vias allowed)
				(pads allowed)
				(copperpour not_allowed)
				(footprints allowed)
			)
			(placement
				(enabled no)
				(sheetname "")
			)
			(fill
				(thermal_gap 0.5)
				(thermal_bridge_width 0.5)
				(island_removal_mode 0)
			)
			(polygon
				(pts
					(arc
						(start 407.303224 19.305524)
						(mid 405.449024 19.305524)
						(end 407.303224 19.305524)
					)
				)
			)
		)
		(zone
			(layers "F.Cu" "B.Cu" "In1.Cu" "In2.Cu" "In3.Cu" "In4.Cu" "In5.Cu" "In6.Cu"
				"In7.Cu" "In8.Cu" "In9.Cu" "In10.Cu" "In11.Cu" "In12.Cu" "In13.Cu" "In14.Cu"
				"In15.Cu" "In16.Cu"
			)
			(hatch none 0.5)
			(connect_pads
				(clearance 0)
			)
			(min_thickness 0.25)
			(keepout
				(tracks not_allowed)
				(vias allowed)
				(pads allowed)
				(copperpour not_allowed)
				(footprints allowed)
			)
			(placement
				(enabled no)
				(sheetname "")
			)
			(fill
				(thermal_gap 0.5)
				(thermal_bridge_width 0.5)
				(island_removal_mode 0)
			)
			(polygon
				(pts
					(arc
						(start 407.303224 21.845524)
						(mid 405.449024 21.845524)
						(end 407.303224 21.845524)
					)
				)
			)
		)
		(zone
			(layer "B.Cu")
			(hatch none 0.5)
			(connect_pads
				(clearance 0)
			)
			(min_thickness 0.25)
			(keepout
				(tracks not_allowed)
				(vias allowed)
				(pads allowed)
				(copperpour not_allowed)
				(footprints allowed)
			)
			(placement
				(enabled no)
				(sheetname "")
			)
			(fill
				(thermal_gap 0.5)
				(thermal_bridge_width 0.5)
				(island_removal_mode 0)
			)
			(polygon
				(pts
					(xy 404.026624 21.124164) (xy 404.026624 21.02866) (xy 403.429724 21.02866) (xy 403.429724 20.62226)
					(xy 404.026624 20.62226) (xy 404.026624 20.528788) (xy 403.429724 20.528788) (xy 403.429724 20.122388)
					(xy 404.026624 20.122388) (xy 404.026624 20.026884) (xy 403.328124 20.026884) (xy 403.328124 21.124164)
				)
			)
		)
	)
	(footprint ""
		(layer "B.Cu")
		(at 362.459016 -319.545462 -90)
		(property "Reference" "R5796"
			(at 0 0 90)
			(layer "B.SilkS")
			(hide yes)
			(effects
				(font
					(size 1.27 1.27)
				)
				(justify mirror)
			)
		)
		(property "Value" ""
			(at 0 0 90)
			(layer "B.Fab")
			(effects
				(font
					(size 1.27 1.27)
				)
				(justify mirror)
			)
		)
		(duplicate_pad_numbers_are_jumpers no)
		(fp_line
			(start -2.576322 1.1303)
			(end 2.576322 1.1303)
			(stroke
				(width 0.1524)
				(type default)
			)
			(layer "B.SilkS")
		)
		(fp_line
			(start 2.576322 1.1303)
			(end 2.576322 -1.1303)
			(stroke
				(width 0.1524)
				(type default)
			)
			(layer "B.SilkS")
		)
		(fp_line
			(start -2.576322 -1.1303)
			(end -2.576322 1.1303)
			(stroke
				(width 0.1524)
				(type default)
			)
			(layer "B.SilkS")
		)
		(fp_line
			(start 2.576322 -1.1303)
			(end -2.576322 -1.1303)
			(stroke
				(width 0.1524)
				(type default)
			)
			(layer "B.SilkS")
		)
		(fp_line
			(start -1.649984 0.899922)
			(end -1.649984 -0.899922)
			(stroke
				(width 0.1)
				(type default)
			)
			(layer "B.Fab")
		)
		(fp_line
			(start 1.649984 0.899922)
			(end -1.649984 0.899922)
			(stroke
				(width 0.1)
				(type default)
			)
			(layer "B.Fab")
		)
		(fp_line
			(start -1.649984 -0.899922)
			(end 1.649984 -0.899922)
			(stroke
				(width 0.1)
				(type default)
			)
			(layer "B.Fab")
		)
		(fp_line
			(start 1.649984 -0.899922)
			(end 1.649984 0.899922)
			(stroke
				(width 0.1)
				(type default)
			)
			(layer "B.Fab")
		)
		(pad "1A" smd rect
			(at 1.700022 0 90)
			(size 1.4986 2.0066)
			(layers "B.Cu" "B.Mask" "B.Paste")
			(net "P0V8_PEX3")
		)
		(pad "1B" smd rect
			(at 1.077722 0 90)
			(size 0.254 0.508)
			(layers "B.Cu" "B.Mask" "B.Paste")
			(net "P0V8_PEX3")
		)
		(pad "2A" smd rect
			(at -1.700022 0 90)
			(size 1.4986 2.0066)
			(layers "B.Cu" "B.Mask" "B.Paste")
			(net "P0V8_SERDES_VDDA_PEX3")
		)
		(pad "2B" smd rect
			(at -1.077722 0 90)
			(size 0.254 0.508)
			(layers "B.Cu" "B.Mask" "B.Paste")
			(net "P0V8_SERDES_VDDA_PEX3")
		)
	)
	(footprint ""
		(layer "B.Cu")
		(at 397.02486 -297.79976 -90)
		(property "Reference" "C1872"
			(at 0 0 90)
			(layer "B.SilkS")
			(hide yes)
			(effects
				(font
					(size 1.27 1.27)
				)
				(justify mirror)
			)
		)
		(property "Value" ""
			(at 0 0 90)
			(layer "B.Fab")
			(effects
				(font
					(size 1.27 1.27)
				)
				(justify mirror)
			)
		)
		(duplicate_pad_numbers_are_jumpers no)
		(fp_line
			(start -0.299974 0.150114)
			(end 0.299974 0.150114)
			(stroke
				(width 0.1)
				(type default)
			)
			(layer "B.Fab")
		)
		(fp_line
			(start 0.299974 0.150114)
			(end 0.299974 -0.150114)
			(stroke
				(width 0.1)
				(type default)
			)
			(layer "B.Fab")
		)
		(fp_line
			(start -0.299974 -0.150114)
			(end -0.299974 0.150114)
			(stroke
				(width 0.1)
				(type default)
			)
			(layer "B.Fab")
		)
		(fp_line
			(start 0.299974 -0.150114)
			(end -0.299974 -0.150114)
			(stroke
				(width 0.1)
				(type default)
			)
			(layer "B.Fab")
		)
		(pad "1" smd rect
			(at 0.2667 0 90)
			(size 0.3048 0.381)
			(layers "B.Cu" "B.Mask" "B.Paste")
			(net "P0V8_PEX3")
		)
		(pad "2" smd rect
			(at -0.2667 0 90)
			(size 0.3048 0.381)
			(layers "B.Cu" "B.Mask" "B.Paste")
			(net "GND")
		)
	)
)
